(kicad_pcb
	(version 20260206)
	(generator "pcbnew")
	(generator_version "10.0")
	(general
		(thickness 1.6)
		(legacy_teardrops no)
	)
	(paper "A4")
	(title_block
		(title "Bryce Canyon_F.DPB_16315-1-OCP.brd")
		(comment 1 "Bryce Canyon / footprint 993 of 2223 (SAS1), pads 291-342 of 342")
	)
	(layers
		(0 "F.Cu" signal "TOP")
		(4 "In1.Cu" signal "L2GND")
		(6 "In2.Cu" signal "L3")
		(8 "In3.Cu" signal "L4GND")
		(10 "In4.Cu" signal "L5")
		(12 "In5.Cu" signal "L6VCC")
		(14 "In6.Cu" signal "L7VCC")
		(16 "In7.Cu" signal "L8")
		(18 "In8.Cu" signal "L9GND")
		(20 "In9.Cu" signal "L10")
		(22 "In10.Cu" signal "L11GND")
		(2 "B.Cu" signal "BOTTOM")
		(9 "F.Adhes" user "F.Adhesive")
		(11 "B.Adhes" user "B.Adhesive")
		(13 "F.Paste" user "Package Geometry/Pastemask Top")
		(15 "B.Paste" user "Package Geometry/Pastemask Bottom")
		(5 "F.SilkS" user "Ref Des/Silkscreen Top")
		(7 "B.SilkS" user "Ref Des/Silkscreen Bottom")
		(1 "F.Mask" user "Board Geometry/Soldermask Top")
		(3 "B.Mask" user "Board Geometry/Soldermask Bottom")
		(17 "Dwgs.User" user "User.Drawings")
		(19 "Cmts.User" user "User.Comments")
		(21 "Eco1.User" user "User.Eco1")
		(23 "Eco2.User" user "User.Eco2")
		(25 "Edge.Cuts" user "Board Geometry/Outline")
		(27 "Margin" user)
		(31 "F.CrtYd" user "Package Geometry/Place Bound Top")
		(29 "B.CrtYd" user "Package Geometry/Place Bound Bottom")
		(35 "F.Fab" user "Ref Des/Assembly Top")
		(33 "B.Fab" user "Ref Des/Assembly Bottom")
	)
	(footprint ""
		(layer "F.Cu")
		(at 287.83661 -357.705152 -90)
		(property "Reference" "SAS1"
			(at 0 0 270)
			(layer "F.SilkS")
			(hide yes)
			(effects
				(font
					(size 1.27 1.27)
				)
			)
		)
		(property "Value" "AMP-CONN342-10R-2-GP"
			(at 20.955 -16.7386 270)
			(unlocked yes)
			(layer "F.Fab")
			(hide yes)
			(effects
				(font
					(size 1.016 1.016)
					(thickness 0.1524)
				)
			)
		)
		(property "Device Type" "PREFIT-342P-668151H483"
			(at 20.955 -18.2626 270)
			(unlocked yes)
			(layer "F.Fab")
			(hide yes)
			(effects
				(font
					(size 1.016 1.016)
					(thickness 0.1524)
				)
			)
		)
		(duplicate_pad_numbers_are_jumpers no)
		(pad "GND75" thru_hole circle
			(at 37.800026 3.50012 270)
			(size 0.762 0.762)
			(drill 0.359918)
			(layers "*.Cu" "*.Mask")
			(remove_unused_layers no)
			(net "GND")
			(clearance 0.1651)
			(thermal_gap 0.1651)
		)
		(pad "GND76" thru_hole circle
			(at 37.800026 7.100062 270)
			(size 0.762 0.762)
			(drill 0.359918)
			(layers "*.Cu" "*.Mask")
			(remove_unused_layers no)
			(net "GND")
			(clearance 0.1651)
			(thermal_gap 0.1651)
		)
		(pad "GND77" thru_hole circle
			(at 37.800026 10.700004 270)
			(size 0.762 0.762)
			(drill 0.359918)
			(layers "*.Cu" "*.Mask")
			(remove_unused_layers no)
			(net "GND")
			(clearance 0.1651)
			(thermal_gap 0.1651)
		)
		(pad "GND78" thru_hole circle
			(at 39.600124 2.500122 270)
			(size 0.762 0.762)
			(drill 0.359918)
			(layers "*.Cu" "*.Mask")
			(remove_unused_layers no)
			(net "GND")
			(clearance 0.1651)
			(thermal_gap 0.1651)
		)
		(pad "GND79" thru_hole circle
			(at 39.600124 6.100064 270)
			(size 0.762 0.762)
			(drill 0.359918)
			(layers "*.Cu" "*.Mask")
			(remove_unused_layers no)
			(net "GND")
			(clearance 0.1651)
			(thermal_gap 0.1651)
		)
		(pad "GND80" thru_hole circle
			(at 39.600124 9.700006 270)
			(size 0.762 0.762)
			(drill 0.359918)
			(layers "*.Cu" "*.Mask")
			(remove_unused_layers no)
			(net "GND")
			(clearance 0.1651)
			(thermal_gap 0.1651)
		)
		(pad "GND81" thru_hole circle
			(at 41.399968 -0.100076 270)
			(size 0.762 0.762)
			(drill 0.359918)
			(layers "*.Cu" "*.Mask")
			(remove_unused_layers no)
			(net "GND")
			(clearance 0.1651)
			(thermal_gap 0.1651)
		)
		(pad "GND82" thru_hole circle
			(at 41.399968 3.50012 270)
			(size 0.762 0.762)
			(drill 0.359918)
			(layers "*.Cu" "*.Mask")
			(remove_unused_layers no)
			(net "GND")
			(clearance 0.1651)
			(thermal_gap 0.1651)
		)
		(pad "GND83" thru_hole circle
			(at 41.399968 7.100062 270)
			(size 0.762 0.762)
			(drill 0.359918)
			(layers "*.Cu" "*.Mask")
			(remove_unused_layers no)
			(net "GND")
			(clearance 0.1651)
			(thermal_gap 0.1651)
		)
		(pad "GND84" thru_hole circle
			(at 41.399968 10.700004 270)
			(size 0.762 0.762)
			(drill 0.359918)
			(layers "*.Cu" "*.Mask")
			(remove_unused_layers no)
			(net "GND")
			(clearance 0.1651)
			(thermal_gap 0.1651)
		)
		(pad "GND85" thru_hole circle
			(at 43.200066 2.500122 270)
			(size 0.762 0.762)
			(drill 0.359918)
			(layers "*.Cu" "*.Mask")
			(remove_unused_layers no)
			(net "GND")
			(clearance 0.1651)
			(thermal_gap 0.1651)
		)
		(pad "GND86" thru_hole circle
			(at 43.200066 6.100064 270)
			(size 0.762 0.762)
			(drill 0.359918)
			(layers "*.Cu" "*.Mask")
			(remove_unused_layers no)
			(net "GND")
			(clearance 0.1651)
			(thermal_gap 0.1651)
		)
		(pad "GND87" thru_hole circle
			(at 43.200066 9.700006 270)
			(size 0.762 0.762)
			(drill 0.359918)
			(layers "*.Cu" "*.Mask")
			(remove_unused_layers no)
			(net "GND")
			(clearance 0.1651)
			(thermal_gap 0.1651)
		)
		(pad "GND88" thru_hole circle
			(at 44.99991 -0.100076 270)
			(size 0.762 0.762)
			(drill 0.359918)
			(layers "*.Cu" "*.Mask")
			(remove_unused_layers no)
			(net "GND")
			(clearance 0.1651)
			(thermal_gap 0.1651)
		)
		(pad "GND89" thru_hole circle
			(at 44.99991 3.50012 270)
			(size 0.762 0.762)
			(drill 0.359918)
			(layers "*.Cu" "*.Mask")
			(remove_unused_layers no)
			(net "GND")
			(clearance 0.1651)
			(thermal_gap 0.1651)
		)
		(pad "GND90" thru_hole circle
			(at 44.99991 7.100062 270)
			(size 0.762 0.762)
			(drill 0.359918)
			(layers "*.Cu" "*.Mask")
			(remove_unused_layers no)
			(net "GND")
			(clearance 0.1651)
			(thermal_gap 0.1651)
		)
		(pad "GND91" thru_hole circle
			(at 44.99991 10.700004 270)
			(size 0.762 0.762)
			(drill 0.359918)
			(layers "*.Cu" "*.Mask")
			(remove_unused_layers no)
			(net "GND")
			(clearance 0.1651)
			(thermal_gap 0.1651)
		)
		(pad "GND92" thru_hole circle
			(at 46.800008 2.500122 270)
			(size 0.762 0.762)
			(drill 0.359918)
			(layers "*.Cu" "*.Mask")
			(remove_unused_layers no)
			(net "GND")
			(clearance 0.1651)
			(thermal_gap 0.1651)
		)
		(pad "GND93" thru_hole circle
			(at 46.800008 6.100064 270)
			(size 0.762 0.762)
			(drill 0.359918)
			(layers "*.Cu" "*.Mask")
			(remove_unused_layers no)
			(net "GND")
			(clearance 0.1651)
			(thermal_gap 0.1651)
		)
		(pad "GND94" thru_hole circle
			(at 46.800008 9.700006 270)
			(size 0.762 0.762)
			(drill 0.359918)
			(layers "*.Cu" "*.Mask")
			(remove_unused_layers no)
			(net "GND")
			(clearance 0.1651)
			(thermal_gap 0.1651)
		)
		(pad "GND95" thru_hole circle
			(at 48.600106 -0.100076 270)
			(size 0.762 0.762)
			(drill 0.359918)
			(layers "*.Cu" "*.Mask")
			(remove_unused_layers no)
			(net "GND")
			(clearance 0.1651)
			(thermal_gap 0.1651)
		)
		(pad "GND96" thru_hole circle
			(at 48.600106 3.50012 270)
			(size 0.762 0.762)
			(drill 0.359918)
			(layers "*.Cu" "*.Mask")
			(remove_unused_layers no)
			(net "GND")
			(clearance 0.1651)
			(thermal_gap 0.1651)
		)
		(pad "GND97" thru_hole circle
			(at 48.600106 7.100062 270)
			(size 0.762 0.762)
			(drill 0.359918)
			(layers "*.Cu" "*.Mask")
			(remove_unused_layers no)
			(net "GND")
			(clearance 0.1651)
			(thermal_gap 0.1651)
		)
		(pad "GND98" thru_hole circle
			(at 48.600106 10.700004 270)
			(size 0.762 0.762)
			(drill 0.359918)
			(layers "*.Cu" "*.Mask")
			(remove_unused_layers no)
			(net "GND")
			(clearance 0.1651)
			(thermal_gap 0.1651)
		)
		(pad "GND99" thru_hole circle
			(at 50.39995 2.500122 270)
			(size 0.762 0.762)
			(drill 0.359918)
			(layers "*.Cu" "*.Mask")
			(remove_unused_layers no)
			(net "GND")
			(clearance 0.1651)
			(thermal_gap 0.1651)
		)
		(pad "GND100" thru_hole circle
			(at 50.39995 6.100064 270)
			(size 0.762 0.762)
			(drill 0.359918)
			(layers "*.Cu" "*.Mask")
			(remove_unused_layers no)
			(net "GND")
			(clearance 0.1651)
			(thermal_gap 0.1651)
		)
		(pad "GND101" thru_hole circle
			(at 50.39995 9.700006 270)
			(size 0.762 0.762)
			(drill 0.359918)
			(layers "*.Cu" "*.Mask")
			(remove_unused_layers no)
			(net "GND")
			(clearance 0.1651)
			(thermal_gap 0.1651)
		)
		(pad "GND102" thru_hole circle
			(at 52.200048 -0.100076 270)
			(size 0.762 0.762)
			(drill 0.359918)
			(layers "*.Cu" "*.Mask")
			(remove_unused_layers no)
			(net "GND")
			(clearance 0.1651)
			(thermal_gap 0.1651)
		)
		(pad "GND103" thru_hole circle
			(at 52.200048 3.50012 270)
			(size 0.762 0.762)
			(drill 0.359918)
			(layers "*.Cu" "*.Mask")
			(remove_unused_layers no)
			(net "GND")
			(clearance 0.1651)
			(thermal_gap 0.1651)
		)
		(pad "GND104" thru_hole circle
			(at 52.200048 7.100062 270)
			(size 0.762 0.762)
			(drill 0.359918)
			(layers "*.Cu" "*.Mask")
			(remove_unused_layers no)
			(net "GND")
			(clearance 0.1651)
			(thermal_gap 0.1651)
		)
		(pad "GND105" thru_hole circle
			(at 52.200048 10.700004 270)
			(size 0.762 0.762)
			(drill 0.359918)
			(layers "*.Cu" "*.Mask")
			(remove_unused_layers no)
			(net "GND")
			(clearance 0.1651)
			(thermal_gap 0.1651)
		)
		(pad "GND106" thru_hole circle
			(at 53.999892 2.500122 270)
			(size 0.762 0.762)
			(drill 0.359918)
			(layers "*.Cu" "*.Mask")
			(remove_unused_layers no)
			(net "GND")
			(clearance 0.1651)
			(thermal_gap 0.1651)
		)
		(pad "GND107" thru_hole circle
			(at 53.999892 6.100064 270)
			(size 0.762 0.762)
			(drill 0.359918)
			(layers "*.Cu" "*.Mask")
			(remove_unused_layers no)
			(net "GND")
			(clearance 0.1651)
			(thermal_gap 0.1651)
		)
		(pad "GND108" thru_hole circle
			(at 53.999892 9.700006 270)
			(size 0.762 0.762)
			(drill 0.359918)
			(layers "*.Cu" "*.Mask")
			(remove_unused_layers no)
			(net "GND")
			(clearance 0.1651)
			(thermal_gap 0.1651)
		)
		(pad "GND109" thru_hole circle
			(at 55.79999 -0.100076 270)
			(size 0.762 0.762)
			(drill 0.359918)
			(layers "*.Cu" "*.Mask")
			(remove_unused_layers no)
			(net "GND")
			(clearance 0.1651)
			(thermal_gap 0.1651)
		)
		(pad "GND110" thru_hole circle
			(at 55.79999 3.50012 270)
			(size 0.762 0.762)
			(drill 0.359918)
			(layers "*.Cu" "*.Mask")
			(remove_unused_layers no)
			(net "GND")
			(clearance 0.1651)
			(thermal_gap 0.1651)
		)
		(pad "GND111" thru_hole circle
			(at 55.79999 7.100062 270)
			(size 0.762 0.762)
			(drill 0.359918)
			(layers "*.Cu" "*.Mask")
			(remove_unused_layers no)
			(net "GND")
			(clearance 0.1651)
			(thermal_gap 0.1651)
		)
		(pad "GND112" thru_hole circle
			(at 55.79999 10.700004 270)
			(size 0.762 0.762)
			(drill 0.359918)
			(layers "*.Cu" "*.Mask")
			(remove_unused_layers no)
			(net "GND")
			(clearance 0.1651)
			(thermal_gap 0.1651)
		)
		(pad "GND113" thru_hole circle
			(at 57.600088 2.500122 270)
			(size 0.762 0.762)
			(drill 0.359918)
			(layers "*.Cu" "*.Mask")
			(remove_unused_layers no)
			(net "GND")
			(clearance 0.1651)
			(thermal_gap 0.1651)
		)
		(pad "GND114" thru_hole circle
			(at 57.600088 6.100064 270)
			(size 0.762 0.762)
			(drill 0.359918)
			(layers "*.Cu" "*.Mask")
			(remove_unused_layers no)
			(net "GND")
			(clearance 0.1651)
			(thermal_gap 0.1651)
		)
		(pad "GND115" thru_hole circle
			(at 57.600088 9.700006 270)
			(size 0.762 0.762)
			(drill 0.359918)
			(layers "*.Cu" "*.Mask")
			(remove_unused_layers no)
			(net "GND")
			(clearance 0.1651)
			(thermal_gap 0.1651)
		)
		(pad "GND116" thru_hole circle
			(at 59.399932 -0.100076 270)
			(size 0.762 0.762)
			(drill 0.359918)
			(layers "*.Cu" "*.Mask")
			(remove_unused_layers no)
			(net "GND")
			(clearance 0.1651)
			(thermal_gap 0.1651)
		)
		(pad "GND117" thru_hole circle
			(at 59.399932 3.50012 270)
			(size 0.762 0.762)
			(drill 0.359918)
			(layers "*.Cu" "*.Mask")
			(remove_unused_layers no)
			(net "GND")
			(clearance 0.1651)
			(thermal_gap 0.1651)
		)
		(pad "GND118" thru_hole circle
			(at 59.399932 7.100062 270)
			(size 0.762 0.762)
			(drill 0.359918)
			(layers "*.Cu" "*.Mask")
			(remove_unused_layers no)
			(net "GND")
			(clearance 0.1651)
			(thermal_gap 0.1651)
		)
		(pad "GND119" thru_hole circle
			(at 59.399932 10.700004 270)
			(size 0.762 0.762)
			(drill 0.359918)
			(layers "*.Cu" "*.Mask")
			(remove_unused_layers no)
			(net "GND")
			(clearance 0.1651)
			(thermal_gap 0.1651)
		)
		(pad "GND120" thru_hole circle
			(at 61.20003 2.500122 270)
			(size 0.762 0.762)
			(drill 0.359918)
			(layers "*.Cu" "*.Mask")
			(remove_unused_layers no)
			(net "GND")
			(clearance 0.1651)
			(thermal_gap 0.1651)
		)
		(pad "GND121" thru_hole circle
			(at 61.20003 6.100064 270)
			(size 0.762 0.762)
			(drill 0.359918)
			(layers "*.Cu" "*.Mask")
			(remove_unused_layers no)
			(net "GND")
			(clearance 0.1651)
			(thermal_gap 0.1651)
		)
		(pad "GND122" thru_hole circle
			(at 61.20003 9.700006 270)
			(size 0.762 0.762)
			(drill 0.359918)
			(layers "*.Cu" "*.Mask")
			(remove_unused_layers no)
			(net "GND")
			(clearance 0.1651)
			(thermal_gap 0.1651)
		)
		(pad "GND123" thru_hole circle
			(at 62.999874 -0.100076 270)
			(size 0.762 0.762)
			(drill 0.359918)
			(layers "*.Cu" "*.Mask")
			(remove_unused_layers no)
			(net "GND")
			(clearance 0.1651)
			(thermal_gap 0.1651)
		)
		(pad "GND124" thru_hole circle
			(at 62.999874 3.50012 270)
			(size 0.762 0.762)
			(drill 0.359918)
			(layers "*.Cu" "*.Mask")
			(remove_unused_layers no)
			(net "GND")
			(clearance 0.1651)
			(thermal_gap 0.1651)
		)
		(pad "GND125" thru_hole circle
			(at 62.999874 7.100062 270)
			(size 0.762 0.762)
			(drill 0.359918)
			(layers "*.Cu" "*.Mask")
			(remove_unused_layers no)
			(net "GND")
			(clearance 0.1651)
			(thermal_gap 0.1651)
		)
		(pad "GND126" thru_hole circle
			(at 62.999874 10.700004 270)
			(size 0.762 0.762)
			(drill 0.359918)
			(layers "*.Cu" "*.Mask")
			(remove_unused_layers no)
			(net "GND")
			(clearance 0.1651)
			(thermal_gap 0.1651)
		)
	)
)
